(kicad_pcb
	(version 20260206)
	(generator "pcbnew")
	(generator_version "10.0")
	(general
		(thickness 1.6)
		(legacy_teardrops no)
	)
	(paper "A4")
	(title_block
		(title "03242023_DA0F0TMBIJ0_F0T_Motherboard_J_brd_V01_OCP.brd")
		(comment 1 "Grand Teton / footprints 5355-5361 of 6105")
	)
	(layers
		(0 "F.Cu" signal "TOP")
		(4 "In1.Cu" signal "GND")
		(6 "In2.Cu" signal "IN1")
		(8 "In3.Cu" signal "GND1")
		(10 "In4.Cu" signal "IN2")
		(12 "In5.Cu" signal "GND2")
		(14 "In6.Cu" signal "IN3")
		(16 "In7.Cu" signal "GND3")
		(18 "In8.Cu" signal "VCC")
		(20 "In9.Cu" signal "VCC1")
		(22 "In10.Cu" signal "GND4")
		(24 "In11.Cu" signal "IN4")
		(26 "In12.Cu" signal "GND5")
		(28 "In13.Cu" signal "IN5")
		(30 "In14.Cu" signal "GND6")
		(32 "In15.Cu" signal "IN6")
		(34 "In16.Cu" signal "GND7")
		(2 "B.Cu" signal "BOTTOM")
		(9 "F.Adhes" user "F.Adhesive")
		(11 "B.Adhes" user "B.Adhesive")
		(13 "F.Paste" user "Package Geometry/Pastemask Top")
		(15 "B.Paste" user "Package Geometry/Pastemask Bottom")
		(5 "F.SilkS" user "Ref Des/Silkscreen Top")
		(7 "B.SilkS" user "Ref Des/Silkscreen Bottom")
		(1 "F.Mask" user "Board Geometry/Soldermask Top")
		(3 "B.Mask" user "Board Geometry/Soldermask Bottom")
		(17 "Dwgs.User" user "User.Drawings")
		(19 "Cmts.User" user "User.Comments")
		(21 "Eco1.User" user "User.Eco1")
		(23 "Eco2.User" user "User.Eco2")
		(25 "Edge.Cuts" user "Board Geometry/Outline")
		(27 "Margin" user)
		(31 "F.CrtYd" user "Package Geometry/Place Bound Top")
		(29 "B.CrtYd" user "Package Geometry/Place Bound Bottom")
		(35 "F.Fab" user "Ref Des/Assembly Top")
		(33 "B.Fab" user "Ref Des/Assembly Bottom")
	)
	(footprint ""
		(layer "B.Cu")
		(at 179.755546 -115.775486 90)
		(property "Reference" "C1915"
			(at 0 0 90)
			(layer "B.SilkS")
			(hide yes)
			(effects
				(font
					(size 1.27 1.27)
				)
				(justify mirror)
			)
		)
		(property "Value" ""
			(at 0 0 90)
			(layer "B.Fab")
			(effects
				(font
					(size 1.27 1.27)
				)
				(justify mirror)
			)
		)
		(duplicate_pad_numbers_are_jumpers no)
		(fp_line
			(start 0.69215 -0.2921)
			(end -0.69215 -0.2921)
			(stroke
				(width 0.1524)
				(type default)
			)
			(layer "B.SilkS")
		)
		(fp_line
			(start -0.69215 -0.2921)
			(end -0.69215 0.2921)
			(stroke
				(width 0.1524)
				(type default)
			)
			(layer "B.SilkS")
		)
		(fp_line
			(start 0.69215 0.2921)
			(end 0.69215 -0.2921)
			(stroke
				(width 0.1524)
				(type default)
			)
			(layer "B.SilkS")
		)
		(fp_line
			(start -0.69215 0.2921)
			(end 0.69215 0.2921)
			(stroke
				(width 0.1524)
				(type default)
			)
			(layer "B.SilkS")
		)
		(fp_line
			(start 0.51435 -0.2794)
			(end -0.51435 -0.2794)
			(stroke
				(width 0.1)
				(type default)
			)
			(layer "B.Fab")
		)
		(fp_line
			(start -0.51435 -0.2794)
			(end -0.51435 0.2794)
			(stroke
				(width 0.1)
				(type default)
			)
			(layer "B.Fab")
		)
		(fp_line
			(start 0.51435 0.2794)
			(end 0.51435 -0.2794)
			(stroke
				(width 0.1)
				(type default)
			)
			(layer "B.Fab")
		)
		(fp_line
			(start -0.51435 0.2794)
			(end 0.51435 0.2794)
			(stroke
				(width 0.1)
				(type default)
			)
			(layer "B.Fab")
		)
		(pad "1" smd circle
			(at 0.40005 0 270)
			(size 0 0)
			(layers "B.Cu" "B.Mask" "B.Paste")
			(net "P3V3_AUX_FPGA_VCCIO1")
		)
		(pad "2" smd circle
			(at -0.40005 0 270)
			(size 0 0)
			(layers "B.Cu" "B.Mask" "B.Paste")
			(net "GND")
		)
		(zone
			(layer "B.Cu")
			(hatch none 0.5)
			(connect_pads
				(clearance 0)
			)
			(min_thickness 0.25)
			(keepout
				(tracks not_allowed)
				(vias allowed)
				(pads allowed)
				(copperpour not_allowed)
				(footprints allowed)
			)
			(placement
				(enabled no)
				(sheetname "")
			)
			(fill
				(thermal_gap 0.5)
				(thermal_bridge_width 0.5)
				(island_removal_mode 0)
			)
			(polygon
				(pts
					(xy 179.843176 -115.965986) (xy 179.901342 -115.874546) (xy 179.901342 -115.675156) (xy 179.843176 -115.584986)
					(xy 179.667916 -115.584986) (xy 179.609496 -115.675156) (xy 179.609496 -115.874546) (xy 179.667662 -115.965986)
				)
			)
		)
	)
	(footprint ""
		(layer "B.Cu")
		(at 295.628314 -319.177416 -90)
		(property "Reference" "R29"
			(at 0 0 90)
			(layer "B.SilkS")
			(hide yes)
			(effects
				(font
					(size 1.27 1.27)
				)
				(justify mirror)
			)
		)
		(property "Value" ""
			(at 0 0 90)
			(layer "B.Fab")
			(effects
				(font
					(size 1.27 1.27)
				)
				(justify mirror)
			)
		)
		(duplicate_pad_numbers_are_jumpers no)
		(fp_line
			(start -0.7874 0.4064)
			(end 0.7874 0.4064)
			(stroke
				(width 0.1524)
				(type default)
			)
			(layer "B.SilkS")
		)
		(fp_line
			(start 0.7874 0.4064)
			(end 0.7874 -0.4064)
			(stroke
				(width 0.1524)
				(type default)
			)
			(layer "B.SilkS")
		)
		(fp_line
			(start -0.7874 -0.4064)
			(end -0.7874 0.4064)
			(stroke
				(width 0.1524)
				(type default)
			)
			(layer "B.SilkS")
		)
		(fp_line
			(start 0.7874 -0.4064)
			(end -0.7874 -0.4064)
			(stroke
				(width 0.1524)
				(type default)
			)
			(layer "B.SilkS")
		)
		(fp_line
			(start -0.67945 0.3048)
			(end -0.120396 0.3048)
			(stroke
				(width 0.1)
				(type default)
			)
			(layer "B.Fab")
		)
		(fp_line
			(start -0.120396 0.3048)
			(end -0.120396 0.2794)
			(stroke
				(width 0.1)
				(type default)
			)
			(layer "B.Fab")
		)
		(fp_line
			(start 0.12065 0.3048)
			(end 0.67945 0.3048)
			(stroke
				(width 0.1)
				(type default)
			)
			(layer "B.Fab")
		)
		(fp_line
			(start 0.67945 0.3048)
			(end 0.67945 -0.305054)
			(stroke
				(width 0.1)
				(type default)
			)
			(layer "B.Fab")
		)
		(fp_line
			(start -0.120396 0.2794)
			(end 0.12065 0.2794)
			(stroke
				(width 0.1)
				(type default)
			)
			(layer "B.Fab")
		)
		(fp_line
			(start 0.12065 0.2794)
			(end 0.12065 0.3048)
			(stroke
				(width 0.1)
				(type default)
			)
			(layer "B.Fab")
		)
		(fp_line
			(start -0.12065 -0.2794)
			(end -0.12065 -0.3048)
			(stroke
				(width 0.1)
				(type default)
			)
			(layer "B.Fab")
		)
		(fp_line
			(start 0.12065 -0.2794)
			(end -0.12065 -0.2794)
			(stroke
				(width 0.1)
				(type default)
			)
			(layer "B.Fab")
		)
		(fp_line
			(start -0.67945 -0.3048)
			(end -0.67945 0.3048)
			(stroke
				(width 0.1)
				(type default)
			)
			(layer "B.Fab")
		)
		(fp_line
			(start -0.12065 -0.3048)
			(end -0.67945 -0.3048)
			(stroke
				(width 0.1)
				(type default)
			)
			(layer "B.Fab")
		)
		(fp_line
			(start 0.12065 -0.305054)
			(end 0.12065 -0.2794)
			(stroke
				(width 0.1)
				(type default)
			)
			(layer "B.Fab")
		)
		(fp_line
			(start 0.67945 -0.305054)
			(end 0.12065 -0.305054)
			(stroke
				(width 0.1)
				(type default)
			)
			(layer "B.Fab")
		)
		(pad "1" smd circle
			(at 0.40005 0 90)
			(size 0 0)
			(layers "B.Cu" "B.Mask" "B.Paste")
			(net "PD_CHB_CPU0_DIMM2_SAA")
		)
		(pad "2" smd circle
			(at -0.40005 0 90)
			(size 0 0)
			(layers "B.Cu" "B.Mask" "B.Paste")
			(net "GND")
		)
	)
	(footprint ""
		(layer "B.Cu")
		(at 178.9557 -110.975394 -90)
		(property "Reference" "C1893"
			(at 0 0 90)
			(layer "B.SilkS")
			(hide yes)
			(effects
				(font
					(size 1.27 1.27)
				)
				(justify mirror)
			)
		)
		(property "Value" ""
			(at 0 0 90)
			(layer "B.Fab")
			(effects
				(font
					(size 1.27 1.27)
				)
				(justify mirror)
			)
		)
		(duplicate_pad_numbers_are_jumpers no)
		(fp_line
			(start -0.69215 0.2921)
			(end 0.69215 0.2921)
			(stroke
				(width 0.1524)
				(type default)
			)
			(layer "B.SilkS")
		)
		(fp_line
			(start 0.69215 0.2921)
			(end 0.69215 -0.2921)
			(stroke
				(width 0.1524)
				(type default)
			)
			(layer "B.SilkS")
		)
		(fp_line
			(start -0.69215 -0.2921)
			(end -0.69215 0.2921)
			(stroke
				(width 0.1524)
				(type default)
			)
			(layer "B.SilkS")
		)
		(fp_line
			(start 0.69215 -0.2921)
			(end -0.69215 -0.2921)
			(stroke
				(width 0.1524)
				(type default)
			)
			(layer "B.SilkS")
		)
		(fp_line
			(start -0.51435 0.2794)
			(end 0.51435 0.2794)
			(stroke
				(width 0.1)
				(type default)
			)
			(layer "B.Fab")
		)
		(fp_line
			(start 0.51435 0.2794)
			(end 0.51435 -0.2794)
			(stroke
				(width 0.1)
				(type default)
			)
			(layer "B.Fab")
		)
		(fp_line
			(start -0.51435 -0.2794)
			(end -0.51435 0.2794)
			(stroke
				(width 0.1)
				(type default)
			)
			(layer "B.Fab")
		)
		(fp_line
			(start 0.51435 -0.2794)
			(end -0.51435 -0.2794)
			(stroke
				(width 0.1)
				(type default)
			)
			(layer "B.Fab")
		)
		(pad "1" smd circle
			(at 0.40005 0 90)
			(size 0 0)
			(layers "B.Cu" "B.Mask" "B.Paste")
			(net "P3V3_AUX_FPGA_VCCIO4")
		)
		(pad "2" smd circle
			(at -0.40005 0 90)
			(size 0 0)
			(layers "B.Cu" "B.Mask" "B.Paste")
			(net "GND")
		)
		(zone
			(layer "B.Cu")
			(hatch none 0.5)
			(connect_pads
				(clearance 0)
			)
			(min_thickness 0.25)
			(keepout
				(tracks not_allowed)
				(vias allowed)
				(pads allowed)
				(copperpour not_allowed)
				(footprints allowed)
			)
			(placement
				(enabled no)
				(sheetname "")
			)
			(fill
				(thermal_gap 0.5)
				(thermal_bridge_width 0.5)
				(island_removal_mode 0)
			)
			(polygon
				(pts
					(xy 178.86807 -110.784894) (xy 178.809904 -110.876334) (xy 178.809904 -111.075724) (xy 178.86807 -111.165894)
					(xy 179.04333 -111.165894) (xy 179.10175 -111.075724) (xy 179.10175 -110.876334) (xy 179.043584 -110.784894)
				)
			)
		)
	)
	(footprint ""
		(layer "B.Cu")
		(at 386.214112 -331.60208 -90)
		(property "Reference" "PC244_P0_8"
			(at 0 0 90)
			(layer "B.SilkS")
			(hide yes)
			(effects
				(font
					(size 1.27 1.27)
				)
				(justify mirror)
			)
		)
		(property "Value" ""
			(at 0 0 90)
			(layer "B.Fab")
			(effects
				(font
					(size 1.27 1.27)
				)
				(justify mirror)
			)
		)
		(duplicate_pad_numbers_are_jumpers no)
		(fp_line
			(start -1.524 0.762)
			(end 1.524 0.762)
			(stroke
				(width 0.1524)
				(type default)
			)
			(layer "B.SilkS")
		)
		(fp_line
			(start 1.524 0.762)
			(end 1.524 -0.762)
			(stroke
				(width 0.1524)
				(type default)
			)
			(layer "B.SilkS")
		)
		(fp_line
			(start -1.524 -0.762)
			(end -1.524 0.762)
			(stroke
				(width 0.1524)
				(type default)
			)
			(layer "B.SilkS")
		)
		(fp_line
			(start 1.524 -0.762)
			(end -1.524 -0.762)
			(stroke
				(width 0.1524)
				(type default)
			)
			(layer "B.SilkS")
		)
		(fp_line
			(start -1.1049 0.724916)
			(end -1.1049 -0.724916)
			(stroke
				(width 0.1)
				(type default)
			)
			(layer "B.Fab")
		)
		(fp_line
			(start 1.1049 0.724916)
			(end -1.1049 0.724916)
			(stroke
				(width 0.1)
				(type default)
			)
			(layer "B.Fab")
		)
		(fp_line
			(start -1.1049 -0.724916)
			(end 1.1049 -0.724916)
			(stroke
				(width 0.1)
				(type default)
			)
			(layer "B.Fab")
		)
		(fp_line
			(start 1.1049 -0.724916)
			(end 1.1049 0.724916)
			(stroke
				(width 0.1)
				(type default)
			)
			(layer "B.Fab")
		)
		(pad "1" smd rect
			(at 0.889 0 270)
			(size 1.016 1.27)
			(layers "B.Cu" "B.Mask" "B.Paste")
			(net "PVCCIN_CPU0")
		)
		(pad "2" smd rect
			(at -0.889 0 270)
			(size 1.016 1.27)
			(layers "B.Cu" "B.Mask" "B.Paste")
			(net "GND")
		)
	)
	(footprint ""
		(layer "B.Cu")
		(at 65.828926 -20.04822)
		(property "Reference" "PC2141"
			(at 0 0 0)
			(layer "B.SilkS")
			(hide yes)
			(effects
				(font
					(size 1.27 1.27)
				)
				(justify mirror)
			)
		)
		(property "Value" ""
			(at 0 0 0)
			(layer "B.Fab")
			(effects
				(font
					(size 1.27 1.27)
				)
				(justify mirror)
			)
		)
		(duplicate_pad_numbers_are_jumpers no)
		(fp_line
			(start -1.524 -0.762)
			(end -1.524 0.762)
			(stroke
				(width 0.1524)
				(type default)
			)
			(layer "B.SilkS")
		)
		(fp_line
			(start -1.524 0.762)
			(end 1.524 0.762)
			(stroke
				(width 0.1524)
				(type default)
			)
			(layer "B.SilkS")
		)
		(fp_line
			(start 1.524 -0.762)
			(end -1.524 -0.762)
			(stroke
				(width 0.1524)
				(type default)
			)
			(layer "B.SilkS")
		)
		(fp_line
			(start 1.524 0.762)
			(end 1.524 -0.762)
			(stroke
				(width 0.1524)
				(type default)
			)
			(layer "B.SilkS")
		)
		(fp_line
			(start -1.1049 -0.724916)
			(end 1.1049 -0.724916)
			(stroke
				(width 0.1)
				(type default)
			)
			(layer "B.Fab")
		)
		(fp_line
			(start -1.1049 0.724916)
			(end -1.1049 -0.724916)
			(stroke
				(width 0.1)
				(type default)
			)
			(layer "B.Fab")
		)
		(fp_line
			(start 1.1049 -0.724916)
			(end 1.1049 0.724916)
			(stroke
				(width 0.1)
				(type default)
			)
			(layer "B.Fab")
		)
		(fp_line
			(start 1.1049 0.724916)
			(end -1.1049 0.724916)
			(stroke
				(width 0.1)
				(type default)
			)
			(layer "B.Fab")
		)
		(pad "1" smd rect
			(at 0.889 0)
			(size 1.016 1.27)
			(layers "B.Cu" "B.Mask" "B.Paste")
			(net "P12V_OCP_V3_2")
		)
		(pad "2" smd rect
			(at -0.889 0)
			(size 1.016 1.27)
			(layers "B.Cu" "B.Mask" "B.Paste")
			(net "GND")
		)
	)
	(footprint ""
		(layer "B.Cu")
		(at 229.761796 -128.866392 180)
		(property "Reference" "R576"
			(at 0 0 0)
			(layer "B.SilkS")
			(hide yes)
			(effects
				(font
					(size 1.27 1.27)
				)
				(justify mirror)
			)
		)
		(property "Value" ""
			(at 0 0 0)
			(layer "B.Fab")
			(effects
				(font
					(size 1.27 1.27)
				)
				(justify mirror)
			)
		)
		(duplicate_pad_numbers_are_jumpers no)
		(fp_line
			(start 0.7874 0.4064)
			(end 0.7874 -0.4064)
			(stroke
				(width 0.1524)
				(type default)
			)
			(layer "B.SilkS")
		)
		(fp_line
			(start 0.7874 -0.4064)
			(end -0.7874 -0.4064)
			(stroke
				(width 0.1524)
				(type default)
			)
			(layer "B.SilkS")
		)
		(fp_line
			(start -0.7874 0.4064)
			(end 0.7874 0.4064)
			(stroke
				(width 0.1524)
				(type default)
			)
			(layer "B.SilkS")
		)
		(fp_line
			(start -0.7874 -0.4064)
			(end -0.7874 0.4064)
			(stroke
				(width 0.1524)
				(type default)
			)
			(layer "B.SilkS")
		)
		(fp_line
			(start 0.67945 0.3048)
			(end 0.67945 -0.305054)
			(stroke
				(width 0.1)
				(type default)
			)
			(layer "B.Fab")
		)
		(fp_line
			(start 0.67945 -0.305054)
			(end 0.12065 -0.305054)
			(stroke
				(width 0.1)
				(type default)
			)
			(layer "B.Fab")
		)
		(fp_line
			(start 0.12065 0.3048)
			(end 0.67945 0.3048)
			(stroke
				(width 0.1)
				(type default)
			)
			(layer "B.Fab")
		)
		(fp_line
			(start 0.12065 0.2794)
			(end 0.12065 0.3048)
			(stroke
				(width 0.1)
				(type default)
			)
			(layer "B.Fab")
		)
		(fp_line
			(start 0.12065 -0.2794)
			(end -0.12065 -0.2794)
			(stroke
				(width 0.1)
				(type default)
			)
			(layer "B.Fab")
		)
		(fp_line
			(start 0.12065 -0.305054)
			(end 0.12065 -0.2794)
			(stroke
				(width 0.1)
				(type default)
			)
			(layer "B.Fab")
		)
		(fp_line
			(start -0.120396 0.3048)
			(end -0.120396 0.2794)
			(stroke
				(width 0.1)
				(type default)
			)
			(layer "B.Fab")
		)
		(fp_line
			(start -0.120396 0.2794)
			(end 0.12065 0.2794)
			(stroke
				(width 0.1)
				(type default)
			)
			(layer "B.Fab")
		)
		(fp_line
			(start -0.12065 -0.2794)
			(end -0.12065 -0.3048)
			(stroke
				(width 0.1)
				(type default)
			)
			(layer "B.Fab")
		)
		(fp_line
			(start -0.12065 -0.3048)
			(end -0.67945 -0.3048)
			(stroke
				(width 0.1)
				(type default)
			)
			(layer "B.Fab")
		)
		(fp_line
			(start -0.67945 0.3048)
			(end -0.120396 0.3048)
			(stroke
				(width 0.1)
				(type default)
			)
			(layer "B.Fab")
		)
		(fp_line
			(start -0.67945 -0.3048)
			(end -0.67945 0.3048)
			(stroke
				(width 0.1)
				(type default)
			)
			(layer "B.Fab")
		)
		(pad "1" smd circle
			(at 0.40005 0)
			(size 0 0)
			(layers "B.Cu" "B.Mask" "B.Paste")
			(net "FM_DB2000_OE_N")
		)
		(pad "2" smd circle
			(at -0.40005 0)
			(size 0 0)
			(layers "B.Cu" "B.Mask" "B.Paste")
			(net "FM_DB2000_1_OE_N")
		)
	)
	(footprint ""
		(layer "B.Cu")
		(at 252.718824 -108.179108 -90)
		(property "Reference" "R1500"
			(at 0 0 90)
			(layer "B.SilkS")
			(hide yes)
			(effects
				(font
					(size 1.27 1.27)
				)
				(justify mirror)
			)
		)
		(property "Value" ""
			(at 0 0 90)
			(layer "B.Fab")
			(effects
				(font
					(size 1.27 1.27)
				)
				(justify mirror)
			)
		)
		(duplicate_pad_numbers_are_jumpers no)
		(fp_line
			(start -0.7874 0.4064)
			(end 0.7874 0.4064)
			(stroke
				(width 0.1524)
				(type default)
			)
			(layer "B.SilkS")
		)
		(fp_line
			(start 0.7874 0.4064)
			(end 0.7874 -0.4064)
			(stroke
				(width 0.1524)
				(type default)
			)
			(layer "B.SilkS")
		)
		(fp_line
			(start -0.7874 -0.4064)
			(end -0.7874 0.4064)
			(stroke
				(width 0.1524)
				(type default)
			)
			(layer "B.SilkS")
		)
		(fp_line
			(start 0.7874 -0.4064)
			(end -0.7874 -0.4064)
			(stroke
				(width 0.1524)
				(type default)
			)
			(layer "B.SilkS")
		)
		(fp_line
			(start -0.67945 0.3048)
			(end -0.120396 0.3048)
			(stroke
				(width 0.1)
				(type default)
			)
			(layer "B.Fab")
		)
		(fp_line
			(start -0.120396 0.3048)
			(end -0.120396 0.2794)
			(stroke
				(width 0.1)
				(type default)
			)
			(layer "B.Fab")
		)
		(fp_line
			(start 0.12065 0.3048)
			(end 0.67945 0.3048)
			(stroke
				(width 0.1)
				(type default)
			)
			(layer "B.Fab")
		)
		(fp_line
			(start 0.67945 0.3048)
			(end 0.67945 -0.305054)
			(stroke
				(width 0.1)
				(type default)
			)
			(layer "B.Fab")
		)
		(fp_line
			(start -0.120396 0.2794)
			(end 0.12065 0.2794)
			(stroke
				(width 0.1)
				(type default)
			)
			(layer "B.Fab")
		)
		(fp_line
			(start 0.12065 0.2794)
			(end 0.12065 0.3048)
			(stroke
				(width 0.1)
				(type default)
			)
			(layer "B.Fab")
		)
		(fp_line
			(start -0.12065 -0.2794)
			(end -0.12065 -0.3048)
			(stroke
				(width 0.1)
				(type default)
			)
			(layer "B.Fab")
		)
		(fp_line
			(start 0.12065 -0.2794)
			(end -0.12065 -0.2794)
			(stroke
				(width 0.1)
				(type default)
			)
			(layer "B.Fab")
		)
		(fp_line
			(start -0.67945 -0.3048)
			(end -0.67945 0.3048)
			(stroke
				(width 0.1)
				(type default)
			)
			(layer "B.Fab")
		)
		(fp_line
			(start -0.12065 -0.3048)
			(end -0.67945 -0.3048)
			(stroke
				(width 0.1)
				(type default)
			)
			(layer "B.Fab")
		)
		(fp_line
			(start 0.12065 -0.305054)
			(end 0.12065 -0.2794)
			(stroke
				(width 0.1)
				(type default)
			)
			(layer "B.Fab")
		)
		(fp_line
			(start 0.67945 -0.305054)
			(end 0.12065 -0.305054)
			(stroke
				(width 0.1)
				(type default)
			)
			(layer "B.Fab")
		)
		(pad "1" smd circle
			(at 0.40005 0 90)
			(size 0 0)
			(layers "B.Cu" "B.Mask" "B.Paste")
			(net "PD_CK440_SBI_DATA_IN")
		)
		(pad "2" smd circle
			(at -0.40005 0 90)
			(size 0 0)
			(layers "B.Cu" "B.Mask" "B.Paste")
			(net "GND")
		)
	)
)
